# BASEBOARD_FAB2 (Tioga Pass) — schematic netlist excerpt (pin names and nets, part order shuffled) for the footprints in the layout excerpt that follows; sources: Cadence DE-HDL packaged netlist, KiCad conversion of Wiwynn_Tioga_Pass_MB.brd

C3M33  CAP  0.22UF 16V 10% X7R  pkg 0402  page 105 : A = P3E_CPU0_PE1_PCH_R_RXN<8> ; B = P3E_CPU0_PE1_PCH_RXN<8>
C25W55  CAP_A  0.1UF 16V 10% X7R  pkg 0402V  page 149 : A = P1V2_AUX_BMC ; B = GND
R6L12  RES  1.00K 1% CHIP  pkg 0402  page 98 : A = M_E_VREF ; B = GND

(kicad_pcb
	(version 20260206)
	(generator "pcbnew")
	(generator_version "10.0")
	(general
		(thickness 1.6)
		(legacy_teardrops no)
	)
	(paper "A4")
	(title_block
		(title "Wiwynn_Tioga_Pass_MB.brd")
		(comment 1 "Tioga Pass / footprints 4197-4199 of 4770")
	)
	(layers
		(0 "F.Cu" signal "TOP")
		(4 "In1.Cu" signal "L2GND")
		(6 "In2.Cu" signal "L3")
		(8 "In3.Cu" signal "L4GND")
		(10 "In4.Cu" signal "L5")
		(12 "In5.Cu" signal "L6GND")
		(14 "In6.Cu" signal "L7VCC")
		(16 "In7.Cu" signal "L8VCC")
		(18 "In8.Cu" signal "L9GND")
		(20 "In9.Cu" signal "L10")
		(22 "In10.Cu" signal "L11GND")
		(24 "In11.Cu" signal "L12")
		(26 "In12.Cu" signal "L13GND")
		(2 "B.Cu" signal "BOTTOM")
		(9 "F.Adhes" user "F.Adhesive")
		(11 "B.Adhes" user "B.Adhesive")
		(13 "F.Paste" user "Package Geometry/Pastemask Top")
		(15 "B.Paste" user "Package Geometry/Pastemask Bottom")
		(5 "F.SilkS" user "Ref Des/Silkscreen Top")
		(7 "B.SilkS" user "Ref Des/Silkscreen Bottom")
		(1 "F.Mask" user "Board Geometry/Soldermask Top")
		(3 "B.Mask" user "Board Geometry/Soldermask Bottom")
		(17 "Dwgs.User" user "User.Drawings")
		(19 "Cmts.User" user "User.Comments")
		(21 "Eco1.User" user "User.Eco1")
		(23 "Eco2.User" user "User.Eco2")
		(25 "Edge.Cuts" user "Board Geometry/Outline")
		(27 "Margin" user)
		(31 "F.CrtYd" user "Package Geometry/Place Bound Top")
		(29 "B.CrtYd" user "Package Geometry/Place Bound Bottom")
		(35 "F.Fab" user "Ref Des/Assembly Top")
		(33 "B.Fab" user "Ref Des/Assembly Bottom")
	)
	(footprint ""
		(layer "B.Cu")
		(at 418.719 -34.3535)
		(property "Reference" "C25W55"
			(at 0.8382 -0.67818 0)
			(unlocked yes)
			(layer "B.SilkS")
			(effects
				(font
					(size 0.4064 0.254)
					(thickness 0.1524)
				)
				(justify left mirror)
			)
		)
		(property "Value" ""
			(at 0 0 0)
			(layer "B.Fab")
			(effects
				(font
					(size 1.27 1.27)
				)
				(justify mirror)
			)
		)
		(duplicate_pad_numbers_are_jumpers no)
		(fp_poly
			(pts
				(xy -0.3048 -0.1016) (xy -0.3048 0.9906) (xy 0.3048 0.9906) (xy 0.3048 -0.1016)
			)
			(stroke
				(width 0)
				(type default)
			)
			(fill no)
			(layer "B.CrtYd")
		)
		(fp_line
			(start -0.3048 -0.1016)
			(end 0.3048 -0.1016)
			(stroke
				(width 0.1)
				(type default)
			)
			(layer "B.Fab")
		)
		(fp_line
			(start -0.3048 0.9906)
			(end -0.3048 -0.1016)
			(stroke
				(width 0.1)
				(type default)
			)
			(layer "B.Fab")
		)
		(fp_line
			(start 0.3048 -0.1016)
			(end 0.3048 0.9906)
			(stroke
				(width 0.1)
				(type default)
			)
			(layer "B.Fab")
		)
		(fp_line
			(start 0.3048 0.9906)
			(end -0.3048 0.9906)
			(stroke
				(width 0.1)
				(type default)
			)
			(layer "B.Fab")
		)
		(pad "1" smd rect
			(at 0 0 180)
			(size 0.508 0.508)
			(layers "B.Cu" "B.Mask" "B.Paste")
			(net "P1V2_AUX_BMC")
		)
		(pad "2" smd rect
			(at 0 0.889 180)
			(size 0.508 0.508)
			(layers "B.Cu" "B.Mask" "B.Paste")
			(net "GND")
		)
		(zone
			(layer "B.Cu")
			(hatch none 0.5)
			(connect_pads
				(clearance 0)
			)
			(min_thickness 0.25)
			(keepout
				(tracks allowed)
				(vias not_allowed)
				(pads allowed)
				(copperpour not_allowed)
				(footprints allowed)
			)
			(placement
				(enabled no)
				(sheetname "")
			)
			(fill
				(thermal_gap 0.5)
				(thermal_bridge_width 0.5)
				(island_removal_mode 0)
			)
			(polygon
				(pts
					(xy 418.973 -34.0995) (xy 418.465 -34.0995) (xy 418.465 -33.7185) (xy 418.973 -33.7185)
				)
			)
		)
		(zone
			(layer "B.Cu")
			(hatch none 0.5)
			(connect_pads
				(clearance 0)
			)
			(min_thickness 0.25)
			(keepout
				(tracks not_allowed)
				(vias allowed)
				(pads allowed)
				(copperpour not_allowed)
				(footprints allowed)
			)
			(placement
				(enabled no)
				(sheetname "")
			)
			(fill
				(thermal_gap 0.5)
				(thermal_bridge_width 0.5)
				(island_removal_mode 0)
			)
			(polygon
				(pts
					(xy 418.973 -33.7185) (xy 418.465 -33.7185) (xy 418.465 -34.0995) (xy 418.973 -34.0995)
				)
			)
		)
	)
	(footprint ""
		(layer "B.Cu")
		(at 368.709956 -122.560842 -90)
		(property "Reference" "C3M33"
			(at 0 0 90)
			(layer "B.SilkS")
			(hide yes)
			(effects
				(font
					(size 1.27 1.27)
				)
				(justify mirror)
			)
		)
		(property "Value" ""
			(at 0 0 90)
			(layer "B.Fab")
			(effects
				(font
					(size 1.27 1.27)
				)
				(justify mirror)
			)
		)
		(duplicate_pad_numbers_are_jumpers no)
		(fp_poly
			(pts
				(xy -0.3048 -0.1016) (xy -0.3048 0.9906) (xy 0.3048 0.9906) (xy 0.3048 -0.1016)
			)
			(stroke
				(width 0)
				(type default)
			)
			(fill no)
			(layer "B.CrtYd")
		)
		(fp_line
			(start -0.3048 0.9906)
			(end -0.3048 -0.1016)
			(stroke
				(width 0.1)
				(type default)
			)
			(layer "B.Fab")
		)
		(fp_line
			(start 0.3048 0.9906)
			(end -0.3048 0.9906)
			(stroke
				(width 0.1)
				(type default)
			)
			(layer "B.Fab")
		)
		(fp_line
			(start -0.3048 -0.1016)
			(end 0.3048 -0.1016)
			(stroke
				(width 0.1)
				(type default)
			)
			(layer "B.Fab")
		)
		(fp_line
			(start 0.3048 -0.1016)
			(end 0.3048 0.9906)
			(stroke
				(width 0.1)
				(type default)
			)
			(layer "B.Fab")
		)
		(pad "1" smd rect
			(at 0 0 90)
			(size 0.508 0.508)
			(layers "B.Cu" "B.Mask" "B.Paste")
			(net "P3E_CPU0_PE1_PCH_R_RXN<8>")
		)
		(pad "2" smd rect
			(at 0 0.889 90)
			(size 0.508 0.508)
			(layers "B.Cu" "B.Mask" "B.Paste")
			(net "P3E_CPU0_PE1_PCH_RXN<8>")
		)
		(zone
			(layer "B.Cu")
			(hatch none 0.5)
			(connect_pads
				(clearance 0)
			)
			(min_thickness 0.25)
			(keepout
				(tracks not_allowed)
				(vias allowed)
				(pads allowed)
				(copperpour not_allowed)
				(footprints allowed)
			)
			(placement
				(enabled no)
				(sheetname "")
			)
			(fill
				(thermal_gap 0.5)
				(thermal_bridge_width 0.5)
				(island_removal_mode 0)
			)
			(polygon
				(pts
					(xy 368.074956 -122.306842) (xy 368.074956 -122.814842) (xy 368.455956 -122.814842) (xy 368.455956 -122.306842)
				)
			)
		)
		(zone
			(layer "B.Cu")
			(hatch none 0.5)
			(connect_pads
				(clearance 0)
			)
			(min_thickness 0.25)
			(keepout
				(tracks allowed)
				(vias not_allowed)
				(pads allowed)
				(copperpour not_allowed)
				(footprints allowed)
			)
			(placement
				(enabled no)
				(sheetname "")
			)
			(fill
				(thermal_gap 0.5)
				(thermal_bridge_width 0.5)
				(island_removal_mode 0)
			)
			(polygon
				(pts
					(xy 368.455956 -122.306842) (xy 368.455956 -122.814842) (xy 368.074956 -122.814842) (xy 368.074956 -122.306842)
				)
			)
		)
	)
	(footprint ""
		(layer "B.Cu")
		(at 194.437 -145.3642)
		(property "Reference" "R6L12"
			(at 0 0 0)
			(layer "B.SilkS")
			(hide yes)
			(effects
				(font
					(size 1.27 1.27)
				)
				(justify mirror)
			)
		)
		(property "Value" ""
			(at 0 0 0)
			(layer "B.Fab")
			(effects
				(font
					(size 1.27 1.27)
				)
				(justify mirror)
			)
		)
		(duplicate_pad_numbers_are_jumpers no)
		(fp_poly
			(pts
				(xy 0.2794 -0.1016) (xy -0.2794 -0.1016) (xy -0.2794 0.9906) (xy 0.2794 0.9906)
			)
			(stroke
				(width 0)
				(type default)
			)
			(fill no)
			(layer "B.CrtYd")
		)
		(fp_line
			(start -0.2794 -0.1016)
			(end 0.2794 -0.1016)
			(stroke
				(width 0.1)
				(type default)
			)
			(layer "B.Fab")
		)
		(fp_line
			(start -0.2794 0.9906)
			(end -0.2794 -0.1016)
			(stroke
				(width 0.1)
				(type default)
			)
			(layer "B.Fab")
		)
		(fp_line
			(start 0.2794 -0.1016)
			(end 0.2794 0.9906)
			(stroke
				(width 0.1)
				(type default)
			)
			(layer "B.Fab")
		)
		(fp_line
			(start 0.2794 0.9906)
			(end -0.2794 0.9906)
			(stroke
				(width 0.1)
				(type default)
			)
			(layer "B.Fab")
		)
		(pad "1" smd rect
			(at 0 0 180)
			(size 0.508 0.508)
			(layers "B.Cu" "B.Mask" "B.Paste")
			(net "M_E_VREF")
		)
		(pad "2" smd rect
			(at 0 0.889 180)
			(size 0.508 0.508)
			(layers "B.Cu" "B.Mask" "B.Paste")
			(net "GND")
		)
		(zone
			(layer "B.Cu")
			(hatch none 0.5)
			(connect_pads
				(clearance 0)
			)
			(min_thickness 0.25)
			(keepout
				(tracks allowed)
				(vias not_allowed)
				(pads allowed)
				(copperpour not_allowed)
				(footprints allowed)
			)
			(placement
				(enabled no)
				(sheetname "")
			)
			(fill
				(thermal_gap 0.5)
				(thermal_bridge_width 0.5)
				(island_removal_mode 0)
			)
			(polygon
				(pts
					(xy 194.691 -145.1102) (xy 194.183 -145.1102) (xy 194.183 -144.7292) (xy 194.691 -144.7292)
				)
			)
		)
		(zone
			(layer "B.Cu")
			(hatch none 0.5)
			(connect_pads
				(clearance 0)
			)
			(min_thickness 0.25)
			(keepout
				(tracks not_allowed)
				(vias allowed)
				(pads allowed)
				(copperpour not_allowed)
				(footprints allowed)
			)
			(placement
				(enabled no)
				(sheetname "")
			)
			(fill
				(thermal_gap 0.5)
				(thermal_bridge_width 0.5)
				(island_removal_mode 0)
			)
			(polygon
				(pts
					(xy 194.691 -144.7292) (xy 194.183 -144.7292) (xy 194.183 -145.1102) (xy 194.691 -145.1102)
				)
			)
		)
	)
)
